(kicad_pcb
	(version 20260206)
	(generator "pcbnew")
	(generator_version "10.0")
	(general
		(thickness 1.6)
		(legacy_teardrops no)
	)
	(paper "A4")
	(title_block
		(title "peb — Lightning_PEB_BRD.brd")
		(comment 1 "Lightning (Wiwynn / Facebook NVMe JBOF) / footprint 1585 of 2563 (U40), pads 1-113 of 408")
	)
	(layers
		(0 "F.Cu" signal "TOP")
		(4 "In1.Cu" signal "L2GND")
		(6 "In2.Cu" signal "L3")
		(8 "In3.Cu" signal "L4VCC")
		(10 "In4.Cu" signal "L5VCC")
		(12 "In5.Cu" signal "L6")
		(14 "In6.Cu" signal "L7GND")
		(2 "B.Cu" signal "BOTTOM")
		(9 "F.Adhes" user "F.Adhesive")
		(11 "B.Adhes" user "B.Adhesive")
		(13 "F.Paste" user "Package Geometry/Pastemask Top")
		(15 "B.Paste" user "Package Geometry/Pastemask Bottom")
		(5 "F.SilkS" user "Ref Des/Silkscreen Top")
		(7 "B.SilkS" user "Ref Des/Silkscreen Bottom")
		(1 "F.Mask" user "Board Geometry/Soldermask Top")
		(3 "B.Mask" user "Board Geometry/Soldermask Bottom")
		(17 "Dwgs.User" user "User.Drawings")
		(19 "Cmts.User" user "User.Comments")
		(21 "Eco1.User" user "User.Eco1")
		(23 "Eco2.User" user "User.Eco2")
		(25 "Edge.Cuts" user "Board Geometry/Outline")
		(27 "Margin" user)
		(31 "F.CrtYd" user "Package Geometry/Place Bound Top")
		(29 "B.CrtYd" user "Package Geometry/Place Bound Bottom")
		(35 "F.Fab" user "Ref Des/Assembly Top")
		(33 "B.Fab" user "Ref Des/Assembly Bottom")
	)
	(footprint ""
		(layer "F.Cu")
		(at 38.104826 -130.48488 180)
		(property "Reference" "U40"
			(at 0 0 180)
			(layer "F.SilkS")
			(hide yes)
			(effects
				(font
					(size 1.27 1.27)
				)
			)
		)
		(property "Value" "AST2400A1-GP"
			(at -17.7292 -6.184392 180)
			(unlocked yes)
			(layer "F.Fab")
			(hide yes)
			(effects
				(font
					(size 1.016 1.016)
					(thickness 0.1524)
				)
			)
		)
		(property "Device Type" "BGA408D19H52"
			(at -17.7292 -7.708392 180)
			(unlocked yes)
			(layer "F.Fab")
			(hide yes)
			(effects
				(font
					(size 1.016 1.016)
					(thickness 0.1524)
				)
			)
		)
		(duplicate_pad_numbers_are_jumpers no)
		(pad "A1" smd circle
			(at -8.400034 -8.400034 180)
			(size 0.4064 0.4064)
			(layers "F.Cu" "F.Mask" "F.Paste")
			(net "BMC0_SDA13_R")
		)
		(pad "A2" smd circle
			(at -7.599934 -8.400034 180)
			(size 0.4064 0.4064)
			(layers "F.Cu" "F.Mask" "F.Paste")
			(net "BMC0_SCL11_R")
		)
		(pad "A3" smd circle
			(at -6.800088 -8.400034 180)
			(size 0.4064 0.4064)
			(layers "F.Cu" "F.Mask" "F.Paste")
			(net "TP_GPIOA6")
		)
		(pad "A4" smd circle
			(at -5.999988 -8.400034 180)
			(size 0.3556 0.3556)
			(layers "F.Cu" "F.Mask" "F.Paste")
			(net "DP_BMC_CPU_RST_N_R")
		)
		(pad "A5" smd circle
			(at -5.199888 -8.400034 180)
			(size 0.3556 0.3556)
			(layers "F.Cu" "F.Mask" "F.Paste")
			(net "Net_192")
		)
		(pad "A6" smd circle
			(at -4.400042 -8.400034 180)
			(size 0.3556 0.3556)
			(layers "F.Cu" "F.Mask" "F.Paste")
			(net "TP_GPIOH6")
		)
		(pad "A7" smd circle
			(at -3.599942 -8.400034 180)
			(size 0.3556 0.3556)
			(layers "F.Cu" "F.Mask" "F.Paste")
			(net "TP_GPIOH3")
		)
		(pad "A8" smd circle
			(at -2.800096 -8.400034 180)
			(size 0.3556 0.3556)
			(layers "F.Cu" "F.Mask" "F.Paste")
			(net "GPIOH0")
		)
		(pad "A9" smd circle
			(at -1.999996 -8.400034 180)
			(size 0.3556 0.3556)
			(layers "F.Cu" "F.Mask" "F.Paste")
			(net "TP_GPIOV4")
		)
		(pad "A10" smd circle
			(at -1.199896 -8.400034 180)
			(size 0.3556 0.3556)
			(layers "F.Cu" "F.Mask" "F.Paste")
			(net "TP_GPIOU0")
		)
		(pad "A11" smd circle
			(at -0.40005 -8.400034 180)
			(size 0.3556 0.3556)
			(layers "F.Cu" "F.Mask" "F.Paste")
			(net "RMII0_BMC_C_CRS_DV")
		)
		(pad "A12" smd circle
			(at 0.40005 -8.400034 180)
			(size 0.3556 0.3556)
			(layers "F.Cu" "F.Mask" "F.Paste")
			(net "RMII0_BMC_C_TX_EN")
		)
		(pad "A13" smd circle
			(at 1.199896 -8.400034 180)
			(size 0.3556 0.3556)
			(layers "F.Cu" "F.Mask" "F.Paste")
			(net "GND")
		)
		(pad "A14" smd circle
			(at 1.999996 -8.400034 180)
			(size 0.3556 0.3556)
			(layers "F.Cu" "F.Mask" "F.Paste")
			(net "HIGH_HEX_0")
		)
		(pad "A15" smd circle
			(at 2.800096 -8.400034 180)
			(size 0.3556 0.3556)
			(layers "F.Cu" "F.Mask" "F.Paste")
			(net "TP_GPIOE3")
		)
		(pad "A16" smd circle
			(at 3.599942 -8.400034 180)
			(size 0.3556 0.3556)
			(layers "F.Cu" "F.Mask" "F.Paste")
			(net "PMC_PLX_BOARD")
		)
		(pad "A17" smd circle
			(at 4.400042 -8.400034 180)
			(size 0.3556 0.3556)
			(layers "F.Cu" "F.Mask" "F.Paste")
			(net "TP_GPIOD3")
		)
		(pad "A18" smd circle
			(at 5.199888 -8.400034 180)
			(size 0.3556 0.3556)
			(layers "F.Cu" "F.Mask" "F.Paste")
			(net "TP_GPIOD0")
		)
		(pad "A19" smd circle
			(at 5.999988 -8.400034 180)
			(size 0.3556 0.3556)
			(layers "F.Cu" "F.Mask" "F.Paste")
			(net "BMC_SSD_RST#12")
		)
		(pad "A20" smd circle
			(at 6.800088 -8.400034 180)
			(size 0.4064 0.4064)
			(layers "F.Cu" "F.Mask" "F.Paste")
			(net "BMC_SSD_RST#9")
		)
		(pad "A21" smd circle
			(at 7.599934 -8.400034 180)
			(size 0.4064 0.4064)
			(layers "F.Cu" "F.Mask" "F.Paste")
			(net "TP_LPC_CPU_FRAME_N")
		)
		(pad "A22" smd circle
			(at 8.400034 -8.400034 180)
			(size 0.4064 0.4064)
			(layers "F.Cu" "F.Mask" "F.Paste")
			(net "TP_BMC0_LPC_LAD1")
		)
		(pad "AA1" smd circle
			(at -8.400034 7.599934 180)
			(size 0.4064 0.4064)
			(layers "F.Cu" "F.Mask" "F.Paste")
			(net "BMC_SSD_RST#5")
		)
		(pad "AA2" smd circle
			(at -7.599934 7.599934 180)
			(size 0.4064 0.4064)
			(layers "F.Cu" "F.Mask" "F.Paste")
			(net "LED_DR_LED1")
		)
		(pad "AA3" smd circle
			(at -6.800088 7.599934 180)
			(size 0.4064 0.4064)
			(layers "F.Cu" "F.Mask" "F.Paste")
			(net "BMC_FW_DET_BOARD_VER_1")
		)
		(pad "AA4" smd circle
			(at -5.999988 7.599934 180)
			(size 0.3556 0.3556)
			(layers "F.Cu" "F.Mask" "F.Paste")
			(net "TP_GPIOO2")
		)
		(pad "AA5" smd circle
			(at -5.199888 7.599934 180)
			(size 0.3556 0.3556)
			(layers "F.Cu" "F.Mask" "F.Paste")
			(net "PEER_BMC_HB")
		)
		(pad "AA6" smd circle
			(at -4.400042 7.599934 180)
			(size 0.3556 0.3556)
			(layers "F.Cu" "F.Mask" "F.Paste")
			(net "BMC_UART_SWITCH_1")
		)
		(pad "AA7" smd circle
			(at -3.599942 7.599934 180)
			(size 0.3556 0.3556)
			(layers "F.Cu" "F.Mask" "F.Paste")
			(net "TP_GPIOP6")
		)
		(pad "AA8" smd circle
			(at -2.800096 7.599934 180)
			(size 0.3556 0.3556)
			(layers "F.Cu" "F.Mask" "F.Paste")
			(net "MEMDQS_P1")
		)
		(pad "AA9" smd circle
			(at -1.999996 7.599934 180)
			(size 0.3556 0.3556)
			(layers "F.Cu" "F.Mask" "F.Paste")
			(net "MEMDQ_10")
		)
		(pad "AA10" smd circle
			(at -1.199896 7.599934 180)
			(size 0.3556 0.3556)
			(layers "F.Cu" "F.Mask" "F.Paste")
			(net "MEMDQS_N0")
		)
		(pad "AA11" smd circle
			(at -0.40005 7.599934 180)
			(size 0.3556 0.3556)
			(layers "F.Cu" "F.Mask" "F.Paste")
			(net "MEMDQ_3")
		)
		(pad "AA12" smd circle
			(at 0.40005 7.599934 180)
			(size 0.3556 0.3556)
			(layers "F.Cu" "F.Mask" "F.Paste")
			(net "MEMCK_N")
		)
		(pad "AA13" smd circle
			(at 1.199896 7.599934 180)
			(size 0.3556 0.3556)
			(layers "F.Cu" "F.Mask" "F.Paste")
			(net "MEMCSN")
		)
		(pad "AA14" smd circle
			(at 1.999996 7.599934 180)
			(size 0.3556 0.3556)
			(layers "F.Cu" "F.Mask" "F.Paste")
			(net "MEMBA_1")
		)
		(pad "AA15" smd circle
			(at 2.800096 7.599934 180)
			(size 0.3556 0.3556)
			(layers "F.Cu" "F.Mask" "F.Paste")
			(net "MEMA_6")
		)
		(pad "AA16" smd circle
			(at 3.599942 7.599934 180)
			(size 0.3556 0.3556)
			(layers "F.Cu" "F.Mask" "F.Paste")
			(net "MEMA_11")
		)
		(pad "AA17" smd circle
			(at 4.400042 7.599934 180)
			(size 0.3556 0.3556)
			(layers "F.Cu" "F.Mask" "F.Paste")
			(net "MEMA_9")
		)
		(pad "AA18" smd circle
			(at 5.199888 7.599934 180)
			(size 0.3556 0.3556)
			(layers "F.Cu" "F.Mask" "F.Paste")
			(net "GND")
		)
		(pad "AA19" smd circle
			(at 5.999988 7.599934 180)
			(size 0.3556 0.3556)
			(layers "F.Cu" "F.Mask" "F.Paste")
			(net "GND")
		)
		(pad "AA20" smd circle
			(at 6.800088 7.599934 180)
			(size 0.4064 0.4064)
			(layers "F.Cu" "F.Mask" "F.Paste")
			(net "PD_USB2VRES")
		)
		(pad "AA21" smd circle
			(at 7.599934 7.599934 180)
			(size 0.4064 0.4064)
			(layers "F.Cu" "F.Mask" "F.Paste")
			(net "PECI0_R")
		)
		(pad "AA22" smd circle
			(at 8.400034 7.599934 180)
			(size 0.4064 0.4064)
			(layers "F.Cu" "F.Mask" "F.Paste")
			(net "DP_RST_N_R")
		)
		(pad "AB1" smd circle
			(at -8.400034 8.400034 180)
			(size 0.4064 0.4064)
			(layers "F.Cu" "F.Mask" "F.Paste")
			(net "BMC0_LED_DR_R_LED0")
		)
		(pad "AB2" smd circle
			(at -7.599934 8.400034 180)
			(size 0.4064 0.4064)
			(layers "F.Cu" "F.Mask" "F.Paste")
			(net "BMC_FW_DET_BOARD_VER_2")
		)
		(pad "AB3" smd circle
			(at -6.800088 8.400034 180)
			(size 0.4064 0.4064)
			(layers "F.Cu" "F.Mask" "F.Paste")
			(net "HB_OUT_BMC")
		)
		(pad "AB4" smd circle
			(at -5.999988 8.400034 180)
			(size 0.3556 0.3556)
			(layers "F.Cu" "F.Mask" "F.Paste")
			(net "TP_GPIOO6")
		)
		(pad "AB5" smd circle
			(at -5.199888 8.400034 180)
			(size 0.3556 0.3556)
			(layers "F.Cu" "F.Mask" "F.Paste")
			(net "TP_GPIOP1")
		)
		(pad "AB6" smd circle
			(at -4.400042 8.400034 180)
			(size 0.3556 0.3556)
			(layers "F.Cu" "F.Mask" "F.Paste")
			(net "TP_GPIOP4")
		)
		(pad "AB7" smd circle
			(at -3.599942 8.400034 180)
			(size 0.3556 0.3556)
			(layers "F.Cu" "F.Mask" "F.Paste")
			(net "BMC_ENCLOSURE_LED")
		)
		(pad "AB8" smd circle
			(at -2.800096 8.400034 180)
			(size 0.3556 0.3556)
			(layers "F.Cu" "F.Mask" "F.Paste")
			(net "MEMDQS_N1")
		)
		(pad "AB9" smd circle
			(at -1.999996 8.400034 180)
			(size 0.3556 0.3556)
			(layers "F.Cu" "F.Mask" "F.Paste")
			(net "MEMDQ_9")
		)
		(pad "AB10" smd circle
			(at -1.199896 8.400034 180)
			(size 0.3556 0.3556)
			(layers "F.Cu" "F.Mask" "F.Paste")
			(net "MEMDQS_P0")
		)
		(pad "AB11" smd circle
			(at -0.40005 8.400034 180)
			(size 0.3556 0.3556)
			(layers "F.Cu" "F.Mask" "F.Paste")
			(net "MEMDQ_2")
		)
		(pad "AB12" smd circle
			(at 0.40005 8.400034 180)
			(size 0.3556 0.3556)
			(layers "F.Cu" "F.Mask" "F.Paste")
			(net "MEMCK_P")
		)
		(pad "AB13" smd circle
			(at 1.199896 8.400034 180)
			(size 0.3556 0.3556)
			(layers "F.Cu" "F.Mask" "F.Paste")
			(net "MEMCASN")
		)
		(pad "AB14" smd circle
			(at 1.999996 8.400034 180)
			(size 0.3556 0.3556)
			(layers "F.Cu" "F.Mask" "F.Paste")
			(net "MEMA_0")
		)
		(pad "AB15" smd circle
			(at 2.800096 8.400034 180)
			(size 0.3556 0.3556)
			(layers "F.Cu" "F.Mask" "F.Paste")
			(net "MEMA_4")
		)
		(pad "AB16" smd circle
			(at 3.599942 8.400034 180)
			(size 0.3556 0.3556)
			(layers "F.Cu" "F.Mask" "F.Paste")
			(net "MEMA_8")
		)
		(pad "AB17" smd circle
			(at 4.400042 8.400034 180)
			(size 0.3556 0.3556)
			(layers "F.Cu" "F.Mask" "F.Paste")
			(net "MEMA_14")
		)
		(pad "AB18" smd circle
			(at 5.199888 8.400034 180)
			(size 0.3556 0.3556)
			(layers "F.Cu" "F.Mask" "F.Paste")
			(net "MEMA_7")
		)
		(pad "AB19" smd circle
			(at 5.999988 8.400034 180)
			(size 0.3556 0.3556)
			(layers "F.Cu" "F.Mask" "F.Paste")
			(net "MPLLAV33")
		)
		(pad "AB20" smd circle
			(at 6.800088 8.400034 180)
			(size 0.4064 0.4064)
			(layers "F.Cu" "F.Mask" "F.Paste")
			(net "BMC_USB2_HDN")
		)
		(pad "AB21" smd circle
			(at 7.599934 8.400034 180)
			(size 0.4064 0.4064)
			(layers "F.Cu" "F.Mask" "F.Paste")
			(net "BMC_USB2_HDP")
		)
		(pad "AB22" smd circle
			(at 8.400034 8.400034 180)
			(size 0.4064 0.4064)
			(layers "F.Cu" "F.Mask" "F.Paste")
			(net "OSC0_AS_CLKIN")
		)
		(pad "B1" smd circle
			(at -8.400034 -7.599934 180)
			(size 0.4064 0.4064)
			(layers "F.Cu" "F.Mask" "F.Paste")
			(net "BMC0_SMB4_CLK")
		)
		(pad "B2" smd circle
			(at -7.599934 -7.599934 180)
			(size 0.4064 0.4064)
			(layers "F.Cu" "F.Mask" "F.Paste")
			(net "BMC0_SCL13_R")
		)
		(pad "B3" smd circle
			(at -6.800088 -7.599934 180)
			(size 0.4064 0.4064)
			(layers "F.Cu" "F.Mask" "F.Paste")
			(net "BMC0_SMB10_DAT")
		)
		(pad "B4" smd circle
			(at -5.999988 -7.599934 180)
			(size 0.3556 0.3556)
			(layers "F.Cu" "F.Mask" "F.Paste")
			(net "BMC0_SMB9_DAT")
		)
		(pad "B5" smd circle
			(at -5.199888 -7.599934 180)
			(size 0.3556 0.3556)
			(layers "F.Cu" "F.Mask" "F.Paste")
			(net "BMC_JTAG_L_EN_R")
		)
		(pad "B6" smd circle
			(at -4.400042 -7.599934 180)
			(size 0.3556 0.3556)
			(layers "F.Cu" "F.Mask" "F.Paste")
			(net "TP_GPIOH5")
		)
		(pad "B7" smd circle
			(at -3.599942 -7.599934 180)
			(size 0.3556 0.3556)
			(layers "F.Cu" "F.Mask" "F.Paste")
			(net "GPIOH2_R")
		)
		(pad "B8" smd circle
			(at -2.800096 -7.599934 180)
			(size 0.3556 0.3556)
			(layers "F.Cu" "F.Mask" "F.Paste")
			(net "TP_RGMIICK")
		)
		(pad "B9" smd circle
			(at -1.999996 -7.599934 180)
			(size 0.3556 0.3556)
			(layers "F.Cu" "F.Mask" "F.Paste")
			(net "TP_GPIOV3")
		)
		(pad "B10" smd circle
			(at -1.199896 -7.599934 180)
			(size 0.3556 0.3556)
			(layers "F.Cu" "F.Mask" "F.Paste")
			(net "TP_GPIOU1")
		)
		(pad "B11" smd circle
			(at -0.40005 -7.599934 180)
			(size 0.3556 0.3556)
			(layers "F.Cu" "F.Mask" "F.Paste")
			(net "RMII_PHY_BMC_RXD1")
		)
		(pad "B12" smd circle
			(at 0.40005 -7.599934 180)
			(size 0.3556 0.3556)
			(layers "F.Cu" "F.Mask" "F.Paste")
			(net "GND")
		)
		(pad "B13" smd circle
			(at 1.199896 -7.599934 180)
			(size 0.3556 0.3556)
			(layers "F.Cu" "F.Mask" "F.Paste")
			(net "FM_TPM_PRES_N_R")
		)
		(pad "B14" smd circle
			(at 1.999996 -7.599934 180)
			(size 0.3556 0.3556)
			(layers "F.Cu" "F.Mask" "F.Paste")
			(net "TP_GPIOE7")
		)
		(pad "B15" smd circle
			(at 2.800096 -7.599934 180)
			(size 0.3556 0.3556)
			(layers "F.Cu" "F.Mask" "F.Paste")
			(net "TP_GPIOE2")
		)
		(pad "B16" smd circle
			(at 3.599942 -7.599934 180)
			(size 0.3556 0.3556)
			(layers "F.Cu" "F.Mask" "F.Paste")
			(net "TP_GPIOD5")
		)
		(pad "B17" smd circle
			(at 4.400042 -7.599934 180)
			(size 0.3556 0.3556)
			(layers "F.Cu" "F.Mask" "F.Paste")
			(net "TP_GPIOD2")
		)
		(pad "B18" smd circle
			(at 5.199888 -7.599934 180)
			(size 0.3556 0.3556)
			(layers "F.Cu" "F.Mask" "F.Paste")
			(net "BMC_SSD_RST#11")
		)
		(pad "B19" smd circle
			(at 5.999988 -7.599934 180)
			(size 0.3556 0.3556)
			(layers "F.Cu" "F.Mask" "F.Paste")
			(net "BMC_SSD_RST#8")
		)
		(pad "B20" smd circle
			(at 6.800088 -7.599934 180)
			(size 0.4064 0.4064)
			(layers "F.Cu" "F.Mask" "F.Paste")
			(net "TP_LPC_CPU_CLKOUT0")
		)
		(pad "B21" smd circle
			(at 7.599934 -7.599934 180)
			(size 0.4064 0.4064)
			(layers "F.Cu" "F.Mask" "F.Paste")
			(net "TP_BMC0_LPC_LAD0")
		)
		(pad "B22" smd circle
			(at 8.400034 -7.599934 180)
			(size 0.4064 0.4064)
			(layers "F.Cu" "F.Mask" "F.Paste")
			(net "SPICS0_N_R")
		)
		(pad "C1" smd circle
			(at -8.400034 -6.800088 180)
			(size 0.4064 0.4064)
			(layers "F.Cu" "F.Mask" "F.Paste")
			(net "BMC0_SMB6_CLK")
		)
		(pad "C2" smd circle
			(at -7.599934 -6.800088 180)
			(size 0.4064 0.4064)
			(layers "F.Cu" "F.Mask" "F.Paste")
			(net "BMC0_SMB3_DAT")
		)
		(pad "C3" smd circle
			(at -6.800088 -6.800088 180)
			(size 0.4064 0.4064)
			(layers "F.Cu" "F.Mask" "F.Paste")
			(net "BMC0_SDA12_R")
		)
		(pad "C4" smd circle
			(at -5.999988 -6.800088 180)
			(size 0.3556 0.3556)
			(layers "F.Cu" "F.Mask" "F.Paste")
			(net "BMC0_SMB10_CLK")
		)
		(pad "C5" smd circle
			(at -5.199888 -6.800088 180)
			(size 0.3556 0.3556)
			(layers "F.Cu" "F.Mask" "F.Paste")
			(net "BMC0_SMB9_CLK")
		)
		(pad "C6" smd circle
			(at -4.400042 -6.800088 180)
			(size 0.3556 0.3556)
			(layers "F.Cu" "F.Mask" "F.Paste")
			(net "Net_191")
		)
		(pad "C7" smd circle
			(at -3.599942 -6.800088 180)
			(size 0.3556 0.3556)
			(layers "F.Cu" "F.Mask" "F.Paste")
			(net "BMC_ID_LED")
		)
		(pad "C8" smd circle
			(at -2.800096 -6.800088 180)
			(size 0.3556 0.3556)
			(layers "F.Cu" "F.Mask" "F.Paste")
			(net "TP_GPIOV7")
		)
		(pad "C9" smd circle
			(at -1.999996 -6.800088 180)
			(size 0.3556 0.3556)
			(layers "F.Cu" "F.Mask" "F.Paste")
			(net "CLK_50M_BMC_NCSI_R")
		)
		(pad "C10" smd circle
			(at -1.199896 -6.800088 180)
			(size 0.3556 0.3556)
			(layers "F.Cu" "F.Mask" "F.Paste")
			(net "TP_GPIOU2")
		)
		(pad "C11" smd circle
			(at -0.40005 -6.800088 180)
			(size 0.3556 0.3556)
			(layers "F.Cu" "F.Mask" "F.Paste")
			(net "RMII_PHY_BMC_RXD0")
		)
		(pad "C12" smd circle
			(at 0.40005 -6.800088 180)
			(size 0.3556 0.3556)
			(layers "F.Cu" "F.Mask" "F.Paste")
			(net "RMII0_BMC_C_PHY_TXD0")
		)
		(pad "C13" smd circle
			(at 1.199896 -6.800088 180)
			(size 0.3556 0.3556)
			(layers "F.Cu" "F.Mask" "F.Paste")
			(net "HIGH_HEX_3")
		)
		(pad "C14" smd circle
			(at 1.999996 -6.800088 180)
			(size 0.3556 0.3556)
			(layers "F.Cu" "F.Mask" "F.Paste")
			(net "TP_GPIOE6")
		)
		(pad "C15" smd circle
			(at 2.800096 -6.800088 180)
			(size 0.3556 0.3556)
			(layers "F.Cu" "F.Mask" "F.Paste")
			(net "TP_GPIOE1")
		)
		(pad "C16" smd circle
			(at 3.599942 -6.800088 180)
			(size 0.3556 0.3556)
			(layers "F.Cu" "F.Mask" "F.Paste")
			(net "TP_GPIOD4")
		)
		(pad "C17" smd circle
			(at 4.400042 -6.800088 180)
			(size 0.3556 0.3556)
			(layers "F.Cu" "F.Mask" "F.Paste")
			(net "BMC_SSD_RST#14")
		)
		(pad "C18" smd circle
			(at 5.199888 -6.800088 180)
			(size 0.3556 0.3556)
			(layers "F.Cu" "F.Mask" "F.Paste")
			(net "SPIDO_R")
		)
		(pad "C19" smd circle
			(at 5.999988 -6.800088 180)
			(size 0.3556 0.3556)
			(layers "F.Cu" "F.Mask" "F.Paste")
			(net "TP_BMC0_LPC_LAD3")
		)
		(pad "C20" smd circle
			(at 6.800088 -6.800088 180)
			(size 0.4064 0.4064)
			(layers "F.Cu" "F.Mask" "F.Paste")
			(net "PWGD_P0V9_E_PG_R")
		)
		(pad "C21" smd circle
			(at 7.599934 -6.800088 180)
			(size 0.4064 0.4064)
			(layers "F.Cu" "F.Mask" "F.Paste")
			(net "SPI_FLASH_SELECT")
		)
		(pad "C22" smd circle
			(at 8.400034 -6.800088 180)
			(size 0.4064 0.4064)
			(layers "F.Cu" "F.Mask" "F.Paste")
			(net "TP_GPIOI0")
		)
		(pad "D1" smd circle
			(at -8.400034 -5.999988 180)
			(size 0.3556 0.3556)
			(layers "F.Cu" "F.Mask" "F.Paste")
			(net "BMC0_SMB7_DAT")
		)
		(pad "D2" smd circle
			(at -7.599934 -5.999988 180)
			(size 0.3556 0.3556)
			(layers "F.Cu" "F.Mask" "F.Paste")
			(net "BMC0_SMB5_DAT")
		)
		(pad "D3" smd circle
			(at -6.800088 -5.999988 180)
			(size 0.3556 0.3556)
			(layers "F.Cu" "F.Mask" "F.Paste")
			(net "BMC0_SMB3_CLK")
		)
	)
)
